# BASEBOARD_FAB2 (Tioga Pass) — schematic netlist excerpt (pin names and nets, part order shuffled) for the footprints in the layout excerpt that follows; sources: Cadence DE-HDL packaged netlist, KiCad conversion of Wiwynn_Tioga_Pass_MB.brd

C5P10  CAP  100UF 4V 20% X5R  pkg 0805  page 42 : A = PVCCMCP_CPU0 ; B = GND
C8L7  CAP_A  47UF 4V 20% X5R  pkg 0603V  page 228 : A = PVDDQ_KLM ; B = GND
R3T4  RES  10.0K 1% CHIP  pkg 0402  page 153 : A = P3V3_STBY ; B = PU_BIOS_SPI_HOLD1_N

(kicad_pcb
	(version 20260206)
	(generator "pcbnew")
	(generator_version "10.0")
	(general
		(thickness 1.6)
		(legacy_teardrops no)
	)
	(paper "A4")
	(title_block
		(title "Wiwynn_Tioga_Pass_MB.brd")
		(comment 1 "Tioga Pass / footprints 2491-2493 of 4770")
	)
	(layers
		(0 "F.Cu" signal "TOP")
		(4 "In1.Cu" signal "L2GND")
		(6 "In2.Cu" signal "L3")
		(8 "In3.Cu" signal "L4GND")
		(10 "In4.Cu" signal "L5")
		(12 "In5.Cu" signal "L6GND")
		(14 "In6.Cu" signal "L7VCC")
		(16 "In7.Cu" signal "L8VCC")
		(18 "In8.Cu" signal "L9GND")
		(20 "In9.Cu" signal "L10")
		(22 "In10.Cu" signal "L11GND")
		(24 "In11.Cu" signal "L12")
		(26 "In12.Cu" signal "L13GND")
		(2 "B.Cu" signal "BOTTOM")
		(9 "F.Adhes" user "F.Adhesive")
		(11 "B.Adhes" user "B.Adhesive")
		(13 "F.Paste" user "Package Geometry/Pastemask Top")
		(15 "B.Paste" user "Package Geometry/Pastemask Bottom")
		(5 "F.SilkS" user "Ref Des/Silkscreen Top")
		(7 "B.SilkS" user "Ref Des/Silkscreen Bottom")
		(1 "F.Mask" user "Board Geometry/Soldermask Top")
		(3 "B.Mask" user "Board Geometry/Soldermask Bottom")
		(17 "Dwgs.User" user "User.Drawings")
		(19 "Cmts.User" user "User.Comments")
		(21 "Eco1.User" user "User.Eco1")
		(23 "Eco2.User" user "User.Eco2")
		(25 "Edge.Cuts" user "Board Geometry/Outline")
		(27 "Margin" user)
		(31 "F.CrtYd" user "Package Geometry/Place Bound Top")
		(29 "B.CrtYd" user "Package Geometry/Place Bound Bottom")
		(35 "F.Fab" user "Ref Des/Assembly Top")
		(33 "B.Fab" user "Ref Des/Assembly Bottom")
	)
	(footprint ""
		(layer "B.Cu")
		(at 275.389086 -79.60614 180)
		(property "Reference" "C5P10"
			(at 0 0 0)
			(layer "B.SilkS")
			(hide yes)
			(effects
				(font
					(size 1.27 1.27)
				)
				(justify mirror)
			)
		)
		(property "Value" ""
			(at 0 0 0)
			(layer "B.Fab")
			(effects
				(font
					(size 1.27 1.27)
				)
				(justify mirror)
			)
		)
		(duplicate_pad_numbers_are_jumpers no)
		(fp_poly
			(pts
				(xy 0.7239 -0.2159) (xy -0.7239 -0.2159) (xy -0.7239 1.9939) (xy 0.7239 1.9939)
			)
			(stroke
				(width 0)
				(type default)
			)
			(fill no)
			(layer "B.CrtYd")
		)
		(fp_line
			(start 0.7239 1.9939)
			(end -0.7239 1.9939)
			(stroke
				(width 0.1)
				(type default)
			)
			(layer "B.Fab")
		)
		(fp_line
			(start 0.7239 -0.2159)
			(end 0.7239 1.9939)
			(stroke
				(width 0.1)
				(type default)
			)
			(layer "B.Fab")
		)
		(fp_line
			(start -0.7239 1.9939)
			(end -0.7239 -0.2159)
			(stroke
				(width 0.1)
				(type default)
			)
			(layer "B.Fab")
		)
		(fp_line
			(start -0.7239 -0.2159)
			(end 0.7239 -0.2159)
			(stroke
				(width 0.1)
				(type default)
			)
			(layer "B.Fab")
		)
		(pad "1" smd rect
			(at 0 0)
			(size 1.27 1.016)
			(layers "B.Cu" "B.Mask" "B.Paste")
			(net "PVCCMCP_CPU0")
		)
		(pad "2" smd rect
			(at 0 1.778)
			(size 1.27 1.016)
			(layers "B.Cu" "B.Mask" "B.Paste")
			(net "GND")
		)
		(zone
			(layer "B.Cu")
			(hatch none 0.5)
			(connect_pads
				(clearance 0)
			)
			(min_thickness 0.25)
			(keepout
				(tracks not_allowed)
				(vias allowed)
				(pads allowed)
				(copperpour not_allowed)
				(footprints allowed)
			)
			(placement
				(enabled no)
				(sheetname "")
			)
			(fill
				(thermal_gap 0.5)
				(thermal_bridge_width 0.5)
				(island_removal_mode 0)
			)
			(polygon
				(pts
					(xy 274.754086 -80.11414) (xy 276.024086 -80.11414) (xy 276.024086 -80.87614) (xy 274.754086 -80.87614)
				)
			)
		)
	)
	(footprint ""
		(layer "B.Cu")
		(at 88.392 -145.0086 90)
		(property "Reference" "C8L7"
			(at -1.848866 0.752348 90)
			(unlocked yes)
			(layer "B.SilkS")
			(effects
				(font
					(size 1.27 0.9652)
					(thickness 0.1524)
				)
				(justify mirror)
			)
		)
		(property "Value" ""
			(at 0 0 90)
			(layer "B.Fab")
			(effects
				(font
					(size 1.27 1.27)
				)
				(justify mirror)
			)
		)
		(duplicate_pad_numbers_are_jumpers no)
		(fp_rect
			(start 0.500126 1.598422)
			(end -0.500126 -0.201422)
			(stroke
				(width 0)
				(type default)
			)
			(fill no)
			(layer "B.CrtYd")
		)
		(fp_line
			(start 0.500126 -0.201422)
			(end -0.500126 -0.201422)
			(stroke
				(width 0.1)
				(type default)
			)
			(layer "B.Fab")
		)
		(fp_line
			(start -0.500126 -0.201422)
			(end -0.500126 1.598422)
			(stroke
				(width 0.1)
				(type default)
			)
			(layer "B.Fab")
		)
		(fp_line
			(start 0.500126 1.598422)
			(end 0.500126 -0.201422)
			(stroke
				(width 0.1)
				(type default)
			)
			(layer "B.Fab")
		)
		(fp_line
			(start -0.500126 1.598422)
			(end 0.500126 1.598422)
			(stroke
				(width 0.1)
				(type default)
			)
			(layer "B.Fab")
		)
		(pad "1" smd rect
			(at 0 0)
			(size 0.889 0.9906)
			(layers "B.Cu" "B.Mask" "B.Paste")
			(net "PVDDQ_KLM")
		)
		(pad "2" smd rect
			(at 0 1.397)
			(size 0.889 0.9906)
			(layers "B.Cu" "B.Mask" "B.Paste")
			(net "GND")
		)
		(zone
			(layer "B.Cu")
			(hatch none 0.5)
			(connect_pads
				(clearance 0)
			)
			(min_thickness 0.25)
			(keepout
				(tracks not_allowed)
				(vias allowed)
				(pads allowed)
				(copperpour not_allowed)
				(footprints allowed)
			)
			(placement
				(enabled no)
				(sheetname "")
			)
			(fill
				(thermal_gap 0.5)
				(thermal_bridge_width 0.5)
				(island_removal_mode 0)
			)
			(polygon
				(pts
					(xy 89.3445 -145.5039) (xy 88.8365 -145.5039) (xy 88.8365 -144.5133) (xy 89.3445 -144.5133)
				)
			)
		)
		(zone
			(layer "B.Cu")
			(hatch none 0.5)
			(connect_pads
				(clearance 0)
			)
			(min_thickness 0.25)
			(keepout
				(tracks allowed)
				(vias not_allowed)
				(pads allowed)
				(copperpour not_allowed)
				(footprints allowed)
			)
			(placement
				(enabled no)
				(sheetname "")
			)
			(fill
				(thermal_gap 0.5)
				(thermal_bridge_width 0.5)
				(island_removal_mode 0)
			)
			(polygon
				(pts
					(xy 89.3445 -145.5039) (xy 88.8365 -145.5039) (xy 88.8365 -144.5133) (xy 89.3445 -144.5133)
				)
			)
		)
	)
	(footprint ""
		(layer "B.Cu")
		(at 399.923 -55.118 180)
		(property "Reference" "R3T4"
			(at 0 0 0)
			(layer "B.SilkS")
			(hide yes)
			(effects
				(font
					(size 1.27 1.27)
				)
				(justify mirror)
			)
		)
		(property "Value" ""
			(at 0 0 0)
			(layer "B.Fab")
			(effects
				(font
					(size 1.27 1.27)
				)
				(justify mirror)
			)
		)
		(duplicate_pad_numbers_are_jumpers no)
		(fp_poly
			(pts
				(xy 0.2794 -0.1016) (xy -0.2794 -0.1016) (xy -0.2794 0.9906) (xy 0.2794 0.9906)
			)
			(stroke
				(width 0)
				(type default)
			)
			(fill no)
			(layer "B.CrtYd")
		)
		(fp_line
			(start 0.2794 0.9906)
			(end -0.2794 0.9906)
			(stroke
				(width 0.1)
				(type default)
			)
			(layer "B.Fab")
		)
		(fp_line
			(start 0.2794 -0.1016)
			(end 0.2794 0.9906)
			(stroke
				(width 0.1)
				(type default)
			)
			(layer "B.Fab")
		)
		(fp_line
			(start -0.2794 0.9906)
			(end -0.2794 -0.1016)
			(stroke
				(width 0.1)
				(type default)
			)
			(layer "B.Fab")
		)
		(fp_line
			(start -0.2794 -0.1016)
			(end 0.2794 -0.1016)
			(stroke
				(width 0.1)
				(type default)
			)
			(layer "B.Fab")
		)
		(pad "1" smd rect
			(at 0 0)
			(size 0.508 0.508)
			(layers "B.Cu" "B.Mask" "B.Paste")
			(net "P3V3_STBY")
		)
		(pad "2" smd rect
			(at 0 0.889)
			(size 0.508 0.508)
			(layers "B.Cu" "B.Mask" "B.Paste")
			(net "PU_BIOS_SPI_HOLD1_N")
		)
		(zone
			(layer "B.Cu")
			(hatch none 0.5)
			(connect_pads
				(clearance 0)
			)
			(min_thickness 0.25)
			(keepout
				(tracks not_allowed)
				(vias allowed)
				(pads allowed)
				(copperpour not_allowed)
				(footprints allowed)
			)
			(placement
				(enabled no)
				(sheetname "")
			)
			(fill
				(thermal_gap 0.5)
				(thermal_bridge_width 0.5)
				(island_removal_mode 0)
			)
			(polygon
				(pts
					(xy 399.669 -55.753) (xy 400.177 -55.753) (xy 400.177 -55.372) (xy 399.669 -55.372)
				)
			)
		)
		(zone
			(layer "B.Cu")
			(hatch none 0.5)
			(connect_pads
				(clearance 0)
			)
			(min_thickness 0.25)
			(keepout
				(tracks allowed)
				(vias not_allowed)
				(pads allowed)
				(copperpour not_allowed)
				(footprints allowed)
			)
			(placement
				(enabled no)
				(sheetname "")
			)
			(fill
				(thermal_gap 0.5)
				(thermal_bridge_width 0.5)
				(island_removal_mode 0)
			)
			(polygon
				(pts
					(xy 399.669 -55.372) (xy 400.177 -55.372) (xy 400.177 -55.753) (xy 399.669 -55.753)
				)
			)
		)
	)
)
